# T6G (Grand Teton) — schematic netlist excerpt (pin names and nets, part order shuffled) for the footprints in the layout excerpt that follows; sources: Cadence DE-HDL packaged netlist, KiCad conversion of 04192023_DAF0TMB3IC0_F0TG_MB_C_brd_V02_OCP.brd

R8110  Q_RES  33.2 1% EMPTY  pkg 0402LF  page 267 : A = HSC_D_OC_R2 ; B = A_HSC_LOW_GATE
C594  Q_CAP  4.7UF 6.3V 20% X6S  pkg 0402  page 290 : A = P1V8_CPU0_RT1_1A ; B = GND

(kicad_pcb
	(version 20260206)
	(generator "pcbnew")
	(generator_version "10.0")
	(general
		(thickness 1.6)
		(legacy_teardrops no)
	)
	(paper "A4")
	(title_block
		(title "04192023_DAF0TMB3IC0_F0TG_MB_C_brd_V02_OCP.brd")
		(comment 1 "Grand Teton / footprints 6227-6228 of 8354")
	)
	(layers
		(0 "F.Cu" signal "TOP")
		(4 "In1.Cu" signal "GND")
		(6 "In2.Cu" signal "IN1")
		(8 "In3.Cu" signal "GND1")
		(10 "In4.Cu" signal "IN2")
		(12 "In5.Cu" signal "GND2")
		(14 "In6.Cu" signal "IN3")
		(16 "In7.Cu" signal "GND3")
		(18 "In8.Cu" signal "VCC")
		(20 "In9.Cu" signal "VCC1")
		(22 "In10.Cu" signal "GND4")
		(24 "In11.Cu" signal "IN4")
		(26 "In12.Cu" signal "GND5")
		(28 "In13.Cu" signal "IN5")
		(30 "In14.Cu" signal "GND6")
		(32 "In15.Cu" signal "IN6")
		(34 "In16.Cu" signal "GND7")
		(2 "B.Cu" signal "BOTTOM")
		(9 "F.Adhes" user "F.Adhesive")
		(11 "B.Adhes" user "B.Adhesive")
		(13 "F.Paste" user "Package Geometry/Pastemask Top")
		(15 "B.Paste" user "Package Geometry/Pastemask Bottom")
		(5 "F.SilkS" user "Ref Des/Silkscreen Top")
		(7 "B.SilkS" user "Ref Des/Silkscreen Bottom")
		(1 "F.Mask" user "Board Geometry/Soldermask Top")
		(3 "B.Mask" user "Board Geometry/Soldermask Bottom")
		(17 "Dwgs.User" user "User.Drawings")
		(19 "Cmts.User" user "User.Comments")
		(21 "Eco1.User" user "User.Eco1")
		(23 "Eco2.User" user "User.Eco2")
		(25 "Edge.Cuts" user "Board Geometry/Outline")
		(27 "Margin" user)
		(31 "F.CrtYd" user "Package Geometry/Place Bound Top")
		(29 "B.CrtYd" user "Package Geometry/Place Bound Bottom")
		(35 "F.Fab" user "Ref Des/Assembly Top")
		(33 "B.Fab" user "Ref Des/Assembly Bottom")
	)
	(footprint ""
		(layer "B.Cu")
		(at 184.687972 -428.15764)
		(property "Reference" "R8110"
			(at 0 0 0)
			(layer "B.SilkS")
			(hide yes)
			(effects
				(font
					(size 1.27 1.27)
				)
				(justify mirror)
			)
		)
		(property "Value" ""
			(at 0 0 0)
			(layer "B.Fab")
			(effects
				(font
					(size 1.27 1.27)
				)
				(justify mirror)
			)
		)
		(duplicate_pad_numbers_are_jumpers no)
		(fp_line
			(start -0.7874 -0.4064)
			(end -0.7874 0.4064)
			(stroke
				(width 0.1524)
				(type default)
			)
			(layer "B.SilkS")
		)
		(fp_line
			(start -0.7874 0.4064)
			(end 0.7874 0.4064)
			(stroke
				(width 0.1524)
				(type default)
			)
			(layer "B.SilkS")
		)
		(fp_line
			(start 0.7874 -0.4064)
			(end -0.7874 -0.4064)
			(stroke
				(width 0.1524)
				(type default)
			)
			(layer "B.SilkS")
		)
		(fp_line
			(start 0.7874 0.4064)
			(end 0.7874 -0.4064)
			(stroke
				(width 0.1524)
				(type default)
			)
			(layer "B.SilkS")
		)
		(fp_line
			(start -0.67945 -0.3048)
			(end -0.67945 0.3048)
			(stroke
				(width 0.1)
				(type default)
			)
			(layer "B.Fab")
		)
		(fp_line
			(start -0.67945 0.3048)
			(end -0.120396 0.3048)
			(stroke
				(width 0.1)
				(type default)
			)
			(layer "B.Fab")
		)
		(fp_line
			(start -0.12065 -0.3048)
			(end -0.67945 -0.3048)
			(stroke
				(width 0.1)
				(type default)
			)
			(layer "B.Fab")
		)
		(fp_line
			(start -0.12065 -0.2794)
			(end -0.12065 -0.3048)
			(stroke
				(width 0.1)
				(type default)
			)
			(layer "B.Fab")
		)
		(fp_line
			(start -0.120396 0.2794)
			(end 0.12065 0.2794)
			(stroke
				(width 0.1)
				(type default)
			)
			(layer "B.Fab")
		)
		(fp_line
			(start -0.120396 0.3048)
			(end -0.120396 0.2794)
			(stroke
				(width 0.1)
				(type default)
			)
			(layer "B.Fab")
		)
		(fp_line
			(start 0.12065 -0.305054)
			(end 0.12065 -0.2794)
			(stroke
				(width 0.1)
				(type default)
			)
			(layer "B.Fab")
		)
		(fp_line
			(start 0.12065 -0.2794)
			(end -0.12065 -0.2794)
			(stroke
				(width 0.1)
				(type default)
			)
			(layer "B.Fab")
		)
		(fp_line
			(start 0.12065 0.2794)
			(end 0.12065 0.3048)
			(stroke
				(width 0.1)
				(type default)
			)
			(layer "B.Fab")
		)
		(fp_line
			(start 0.12065 0.3048)
			(end 0.67945 0.3048)
			(stroke
				(width 0.1)
				(type default)
			)
			(layer "B.Fab")
		)
		(fp_line
			(start 0.67945 -0.305054)
			(end 0.12065 -0.305054)
			(stroke
				(width 0.1)
				(type default)
			)
			(layer "B.Fab")
		)
		(fp_line
			(start 0.67945 0.3048)
			(end 0.67945 -0.305054)
			(stroke
				(width 0.1)
				(type default)
			)
			(layer "B.Fab")
		)
		(pad "1" smd circle
			(at 0.40005 0 180)
			(size 0 0)
			(layers "B.Cu" "B.Mask" "B.Paste")
			(net "HSC_D_OC_R2")
		)
		(pad "2" smd circle
			(at -0.40005 0 180)
			(size 0 0)
			(layers "B.Cu" "B.Mask" "B.Paste")
			(net "A_HSC_LOW_GATE")
		)
	)
	(footprint ""
		(layer "B.Cu")
		(at 344.318844 -398.942052 90)
		(property "Reference" "C594"
			(at 0 0 90)
			(layer "B.SilkS")
			(hide yes)
			(effects
				(font
					(size 1.27 1.27)
				)
				(justify mirror)
			)
		)
		(property "Value" ""
			(at 0 0 90)
			(layer "B.Fab")
			(effects
				(font
					(size 1.27 1.27)
				)
				(justify mirror)
			)
		)
		(duplicate_pad_numbers_are_jumpers no)
		(fp_line
			(start 0.7874 -0.4064)
			(end -0.7874 -0.4064)
			(stroke
				(width 0.1524)
				(type default)
			)
			(layer "B.SilkS")
		)
		(fp_line
			(start -0.7874 -0.4064)
			(end -0.7874 0.4064)
			(stroke
				(width 0.1524)
				(type default)
			)
			(layer "B.SilkS")
		)
		(fp_line
			(start 0.7874 0.4064)
			(end 0.7874 -0.4064)
			(stroke
				(width 0.1524)
				(type default)
			)
			(layer "B.SilkS")
		)
		(fp_line
			(start -0.7874 0.4064)
			(end 0.7874 0.4064)
			(stroke
				(width 0.1524)
				(type default)
			)
			(layer "B.SilkS")
		)
		(fp_line
			(start 0.67945 -0.305054)
			(end 0.12065 -0.305054)
			(stroke
				(width 0.1)
				(type default)
			)
			(layer "B.Fab")
		)
		(fp_line
			(start 0.12065 -0.305054)
			(end 0.12065 -0.2794)
			(stroke
				(width 0.1)
				(type default)
			)
			(layer "B.Fab")
		)
		(fp_line
			(start -0.12065 -0.3048)
			(end -0.67945 -0.3048)
			(stroke
				(width 0.1)
				(type default)
			)
			(layer "B.Fab")
		)
		(fp_line
			(start -0.67945 -0.3048)
			(end -0.67945 0.3048)
			(stroke
				(width 0.1)
				(type default)
			)
			(layer "B.Fab")
		)
		(fp_line
			(start 0.12065 -0.2794)
			(end -0.12065 -0.2794)
			(stroke
				(width 0.1)
				(type default)
			)
			(layer "B.Fab")
		)
		(fp_line
			(start -0.12065 -0.2794)
			(end -0.12065 -0.3048)
			(stroke
				(width 0.1)
				(type default)
			)
			(layer "B.Fab")
		)
		(fp_line
			(start 0.12065 0.2794)
			(end 0.12065 0.3048)
			(stroke
				(width 0.1)
				(type default)
			)
			(layer "B.Fab")
		)
		(fp_line
			(start -0.120396 0.2794)
			(end 0.12065 0.2794)
			(stroke
				(width 0.1)
				(type default)
			)
			(layer "B.Fab")
		)
		(fp_line
			(start 0.67945 0.3048)
			(end 0.67945 -0.305054)
			(stroke
				(width 0.1)
				(type default)
			)
			(layer "B.Fab")
		)
		(fp_line
			(start 0.12065 0.3048)
			(end 0.67945 0.3048)
			(stroke
				(width 0.1)
				(type default)
			)
			(layer "B.Fab")
		)
		(fp_line
			(start -0.120396 0.3048)
			(end -0.120396 0.2794)
			(stroke
				(width 0.1)
				(type default)
			)
			(layer "B.Fab")
		)
		(fp_line
			(start -0.67945 0.3048)
			(end -0.120396 0.3048)
			(stroke
				(width 0.1)
				(type default)
			)
			(layer "B.Fab")
		)
		(pad "1" smd circle
			(at 0.40005 0 270)
			(size 0 0)
			(layers "B.Cu" "B.Mask" "B.Paste")
			(net "P1V8_CPU0_RT1_1A")
		)
		(pad "2" smd circle
			(at -0.40005 0 270)
			(size 0 0)
			(layers "B.Cu" "B.Mask" "B.Paste")
			(net "GND")
		)
	)
)
